# S9S_MB_2U (Grand Teton) — schematic netlist excerpt (pin names and nets, part order shuffled) for the footprints in the layout excerpt that follows; sources: Cadence DE-HDL packaged netlist, KiCad conversion of 03242023_DA0F0TMBIJ0_F0T_Motherboard_J_brd_V01_OCP.brd

J41  SCONN168_ME1016810202011  IO  pkg CON_F168S2H7D_P0-6W2-95_LUH  page 240
  GND_A1  = SMB_OCP_SFF_3V3AUX_SCL_R0
  GND_A2  = SMB_OCP_SFF_3V3AUX_SDA_R0
  GND_A3  = SMB_HOST_3V3AUX_SCL_R0
  GND_A4  = SMB_HOST_3V3AUX_SDA_R0
  GND_A5  = SMB_VR_3V3AUX_SCL_R0
  GND_A6  = SMB_VR_3V3AUX_SDA_R0
  SMCLK  = SMB_SML1_PMBUS_3V3AUX_PCH_SCL_R
  SMDAT  = SMB_SML1_PMBUS_3V3AUX_PCH_SDA_R
  \smrst#\  = I3C_BMC_SWB_SCL
  \prsnta#\  = I3C_BMC_SWB_SDA
  \perst1#\  = SMB_OCP_V3_2_3V3AUX_SCL_R0
  \prsntb2#\  = SMB_OCP_V3_2_3V3AUX_SDA_R0
  GND_A13  = GND
  REFCLKN1  = CLK_100M_BMC_P3E_DP_R
  REFCLKP1  = CLK_100M_BMC_P3E_DN_R
  GND_A16  = GND
  PERN0  = P3E_PCH_BMC_TX_C_DP
  PERP0  = P3E_PCH_BMC_TX_C_DN
  GND_A19  = GND
  PERN1  = P3E_PCH_BMC_RX_DP
  PERP1  = P3E_PCH_BMC_RX_DN
  GND_A22  = GND
  PERN2  = SMB_PCIE0_3V3AUX_SCL
  PERP2  = SMB_PCIE0_3V3AUX_SDA
  GND_A25  = SMB_SML0_3V3AUX_SCL_R1
  PERN3  = SMB_SML0_3V3AUX_SDA_R1
  PERP3  = SMB_1_PLD_3V3AUX_SCL_R3
  GND_A28  = SMB_1_PLD_3V3AUX_SDA_R3
  GND_A29  = SMB_FAN_3V3AUX_SCL
  PERN4  = SMB_FAN_3V3AUX_SDA
  PERP4  = SMB_PCIE2_3V3AUX_SCL_R0
  GND_A32  = SMB_PCIE2_3V3AUX_SDA_R0
  PERN5  = GND
  PERP5  = JTAG_BMC_TCK
  GND_A35  = JTAG_BMC_TMS
  PERN6  = JTAG_BMC_TDI
  PERP6  = JTAG_BMC_TDO
  GND_A38  = SMB_PCIE3_3V3AUX_SCL_R
  PERN7  = SMB_PCIE3_3V3AUX_SDA_R
  PERP7  = SMB_S3M_CPU_3V3AUX_SCL_R0
  GND_A41  = SMB_S3M_CPU_3V3AUX_SDA_R0
  \prsntb1#\  = GND
  GND_A43  = FM_JTAG_BMC_MUX_SEL_FROM_BMC_R2
  PERN8  = PWRGD_PS_PWROK_R
  PERP8  = TP_HPM_STBY_EN
  GND_A46  = RST_MB_STBY_N
  PERN9  = FM_BMC_PWRBTN_OUT_R_N
  PERP9  = PWRGD_SYS_PWROK
  GND_A49  = JTAG_BMC_DBP_PREQ_N
  PERN10  = JTAG_DBP_BMC_PRDY_N
  PERP10  = RST_PLTRST_B_N
  GND_A52  = FM_UARTSW_MSB_R
  PERN11  = ROT_P1_RST_IND_N
  PERP11  = FM_BMC_INTRUDER_N
  GND_A55  = FM_UARTSW_LSB_R
  PERN12  = IRQ0_A57
  PERP12  = FM_SCM_PRSNT1_N
  GND_A58  = GND
  PERN13  = USB3_PCH_RX_DP<4>
  PERP13  = USB3_PCH_RX_DN<4>
  GND_A61  = GND
  PERN14  = TP_PCIE_HPM_RXP<1>
  PERP14  = TP_PCIE_HPM_RXN<1>
  GND_A64  = GND
  PERN15  = P2E_MB_BMC_RX_BUF_DP<0>
  PERP15  = P2E_MB_BMC_RX_BUF_DN<0>
  GND_A67  = GND
  USB_DATN  = CLK_100M_BMC_RC_DP
  USB_DATP  = CLK_100M_BMC_RC_DN
  \pwrbrk0#\  = GND
  \+12v_edge_b1\  = ESPI_HOST_LPC_BMC_CLK
  \+12v_edge_b2\  = ESPI_HOST_LPC_BMC_LFRAME_N
  \+12v_edge_b3\  = IRQ_ESPI_LPC_SERIRQ_ALERT_R_N
  \+12v_edge_b4\  = ESPI_BMC_LPC_RST_N
  \+12v_edge_b5\  = ESPI_LPC_LAD0_IO0
  \+12v_edge_b6\  = ESPI_LPC_LAD0_IO1
  \bif0#\  = ESPI_LPC_LAD0_IO2
  \bif1#\  = ESPI_LPC_LAD0_IO3
  \bif2#\  = FM_LPC_ESPI_SEL
  \perst0#\  = GND
  \+3.3v_edge\  = SPI_SYS_CLK
  AUX_PWR_EN  = SPI_SYS_CS0_N
  GND_B13  = SPI_SYS_MOSI
  REFCLKN0  = SPI_SYS_MISO
  REFCLKP0  = SPI_SYS_WP_IO2
  GND_B16  = SPI_SYS_HOLD_IO3
  PETN0  = GND
  PETP0  = CLK_50M_RMII_BMC_OCP
  GND_B19  = RMII_OCP_BMC_CRSDV
  PETN1  = RMII_BMC_OCP_TX_EN
  PETP1  = RMII_BMC_OCP_TXD_0
  GND_B22  = RMII_BMC_OCP_TXD_1
  PETN2  = RMII_BMC_OCP_RX_ER
  PETP2  = RMII_OCP_BMC_RXD_0
  GND_B25  = RMII_OCP_BMC_RXD_1
  PETN3  = GND
  PETP3  = PECI_BMC
  GND_B28  = PVCCIO_PECI_BMC
  GND_B29  = SGPIO_DO_0
  PETN4  = SGPIO_CLK_0
  PETP4  = SGPIO_DI_0
  GND_B32  = SGPIO_LD_0
  PETN5  = GND
  PETP5  = SGPIO_DO_1
  GND_B35  = SGPIO_CLK_1
  PETN6  = SGPIO_DI_1
  PETP6  = SGPIO_LD_1
  GND_B38  = GND
  PETN7  = RST_SGPIO_RESET_N
  PETP7  = IRQ_SGPIO_INTR_N
  GND_B41  = P3V_BAT_R1
  \prsntb0#\  = FM_AC_PWR_BTN_N
  GND_B43  = TP_SPI_2_PLD_CLK
  PETN8  = TP_SPI_2_PLD_CS_N
  PETP8  = TP_SPI_2_PLD_IO0
  GND_B46  = TP_SPI_2_PLD_IO1
  PETN9  = TP_SPI_2_PLD_IO2
  PETP9  = TP_SPI_2_PLD_IO3
  GND_B49  = GND
  PETN10  = USB2_HOST_BMC_B_DP
  PETP10  = USB2_HOST_BMC_B_DN
  GND_B52  = GND
  PETN11  = USB2_8_DP
  PETP11  = USB2_8_DN
  GND_B55  = GND
  PETN12  = USB2_HUB_2_BUF_EXT_DP
  PETP12  = USB2_HUB_2_BUF_EXT_DN
  GND_B58  = GND
  PETN13  = USB3_PCH_TX_BUF_C_DP<4>
  PETP13  = USB3_PCH_TX_BUF_C_DN<4>
  GND_B61  = GND
  PETN14  = TP_PCIE_HPM_TXP<1>
  PETP14  = TP_PCIE_HPM_TXN<1>
  GND_B64  = GND
  PETN15  = P2E_MB_BMC_TX_C_DP<0>
  PETP15  = P2E_MB_BMC_TX_C_DN<0>
  GND_B67  = GND
  RFU1_NC_B68  = TP_PCIE_HPM_TXP<3>
  RFU1_NC_B69  = TP_PCIE_HPM_TXN<3>
  \prsntb3#\  = GND
  G1  = GND
  G2  = GND
  G3  = GND
  G4  = GND
  G5  = GND
  \perst2#\  = P12V_SCM
  \perst3#\  = P12V_SCM
  \wake#\  = GND
  RBT_ARB_IN  = GND
  RBT_ARB_OUT  = I3C_SPD_DDRABCD_CPU0_BMC_R_SCL
  SLOT_ID1  = I3C_SPD_DDRABCD_CPU0_BMC_R_SDA
  RBT_TX_EN  = I3C_SPD_DDREFGH_CPU0_BMC_R_SCL
  RBT_TXD1  = I3C_SPD_DDREFGH_CPU0_BMC_R_SDA
  RBT_TXD0  = I3C_SPD_DDRABCD_CPU1_BMC_R_SCL
  GND_OA10  = I3C_SPD_DDRABCD_CPU1_BMC_R_SDA
  REFCLKN3  = I3C_SPD_DDREFGH_CPU1_BMC_R_SCL
  REFCLKP3  = I3C_SPD_DDREFGH_CPU1_BMC_R_SDA
  GND_OA13  = GND
  RBT_CLK_IN  = VIRTUAL_RESEAT
  NIC_PWR_GOOD  = P12V_SCM
  MAIN_PWR_EN  = P12V_SCM
  \ld#\  = PRSNT0_N
  DATA_IN  = GND
  DATA_OUT  = UART_BMC_BIC_TX
  CLK  = UART_BMC_BIC_BUF_RX
  SLOT_ID0  = GND
  RBT_RXD1  = USB2_7_R_DP
  RBT_RXD0  = USB2_7_R_DN
  GND_OB10  = GND
  REFCLKN2  = RST_SRST_PLD_BMC_N
  REFCLKP2  = SPI_TPM_CS_N
  GND_OB13  = H_CPU_CATERR_LVC2_BMC_N
  RBT_CRS_DV  = FM_SOL_UART_CH_SEL_R

(kicad_pcb
	(version 20260206)
	(generator "pcbnew")
	(generator_version "10.0")
	(general
		(thickness 1.6)
		(legacy_teardrops no)
	)
	(paper "A4")
	(title_block
		(title "03242023_DA0F0TMBIJ0_F0T_Motherboard_J_brd_V01_OCP.brd")
		(comment 1 "Grand Teton / footprint 3077 of 6105 (J41), pads 132-174 of 175")
	)
	(layers
		(0 "F.Cu" signal "TOP")
		(4 "In1.Cu" signal "GND")
		(6 "In2.Cu" signal "IN1")
		(8 "In3.Cu" signal "GND1")
		(10 "In4.Cu" signal "IN2")
		(12 "In5.Cu" signal "GND2")
		(14 "In6.Cu" signal "IN3")
		(16 "In7.Cu" signal "GND3")
		(18 "In8.Cu" signal "VCC")
		(20 "In9.Cu" signal "VCC1")
		(22 "In10.Cu" signal "GND4")
		(24 "In11.Cu" signal "IN4")
		(26 "In12.Cu" signal "GND5")
		(28 "In13.Cu" signal "IN5")
		(30 "In14.Cu" signal "GND6")
		(32 "In15.Cu" signal "IN6")
		(34 "In16.Cu" signal "GND7")
		(2 "B.Cu" signal "BOTTOM")
		(9 "F.Adhes" user "F.Adhesive")
		(11 "B.Adhes" user "B.Adhesive")
		(13 "F.Paste" user "Package Geometry/Pastemask Top")
		(15 "B.Paste" user "Package Geometry/Pastemask Bottom")
		(5 "F.SilkS" user "Ref Des/Silkscreen Top")
		(7 "B.SilkS" user "Ref Des/Silkscreen Bottom")
		(1 "F.Mask" user "Board Geometry/Soldermask Top")
		(3 "B.Mask" user "Board Geometry/Soldermask Bottom")
		(17 "Dwgs.User" user "User.Drawings")
		(19 "Cmts.User" user "User.Comments")
		(21 "Eco1.User" user "User.Eco1")
		(23 "Eco2.User" user "User.Eco2")
		(25 "Edge.Cuts" user "Board Geometry/Outline")
		(27 "Margin" user)
		(31 "F.CrtYd" user "Package Geometry/Place Bound Top")
		(29 "B.CrtYd" user "Package Geometry/Place Bound Bottom")
		(35 "F.Fab" user "Ref Des/Assembly Top")
		(33 "B.Fab" user "Ref Des/Assembly Bottom")
	)
	(footprint ""
		(layer "F.Cu")
		(at 160.402016 -10.850118 -90)
		(property "Reference" "J41"
			(at -12.075414 24.511762 0)
			(unlocked yes)
			(layer "F.SilkS")
			(effects
				(font
					(size 0.7874 0.5842)
					(thickness 0.1524)
				)
				(justify left)
			)
		)
		(property "Value" ""
			(at 0 0 270)
			(layer "F.Fab")
			(effects
				(font
					(size 1.27 1.27)
				)
			)
		)
		(duplicate_pad_numbers_are_jumpers no)
		(pad "B60" smd rect
			(at -5.700014 24.655018 180)
			(size 0.381 1.4478)
			(layers "F.Cu" "F.Mask" "F.Paste")
			(net "USB3_PCH_TX_BUF_C_DN<4>")
		)
		(pad "B61" smd rect
			(at -5.700014 25.254966 180)
			(size 0.381 1.4478)
			(layers "F.Cu" "F.Mask" "F.Paste")
			(net "GND")
		)
		(pad "B62" smd rect
			(at -5.700014 25.854914 180)
			(size 0.381 1.4478)
			(layers "F.Cu" "F.Mask" "F.Paste")
			(net "TP_PCIE_HPM_TXP<1>")
		)
		(pad "B63" smd rect
			(at -5.700014 26.455116 180)
			(size 0.381 1.4478)
			(layers "F.Cu" "F.Mask" "F.Paste")
			(net "TP_PCIE_HPM_TXN<1>")
		)
		(pad "B64" smd rect
			(at -5.700014 27.055064 180)
			(size 0.381 1.4478)
			(layers "F.Cu" "F.Mask" "F.Paste")
			(net "GND")
		)
		(pad "B65" smd rect
			(at -5.700014 27.655012 180)
			(size 0.381 1.4478)
			(layers "F.Cu" "F.Mask" "F.Paste")
			(net "P2E_MB_BMC_TX_C_DP<0>")
		)
		(pad "B66" smd rect
			(at -5.700014 28.25496 180)
			(size 0.381 1.4478)
			(layers "F.Cu" "F.Mask" "F.Paste")
			(net "P2E_MB_BMC_TX_C_DN<0>")
		)
		(pad "B67" smd rect
			(at -5.700014 28.854908 180)
			(size 0.381 1.4478)
			(layers "F.Cu" "F.Mask" "F.Paste")
			(net "GND")
		)
		(pad "B68" smd rect
			(at -5.700014 29.45511 180)
			(size 0.381 1.4478)
			(layers "F.Cu" "F.Mask" "F.Paste")
			(net "TP_PCIE_HPM_TXP<3>")
		)
		(pad "B69" smd rect
			(at -5.700014 30.055058 180)
			(size 0.381 1.4478)
			(layers "F.Cu" "F.Mask" "F.Paste")
			(net "TP_PCIE_HPM_TXN<3>")
		)
		(pad "B70" smd rect
			(at -5.700014 30.655006 180)
			(size 0.381 1.4478)
			(layers "F.Cu" "F.Mask" "F.Paste")
			(net "GND")
		)
		(pad "G1" thru_hole circle
			(at 2.400046 -32.759904 180)
			(size 1.6256 1.6256)
			(drill 1.1176)
			(layers "*.Cu" "*.Mask")
			(remove_unused_layers no)
			(net "GND")
			(clearance 0)
		)
		(pad "G2" thru_hole circle
			(at 2.400046 -20.379944 180)
			(size 1.6256 1.6256)
			(drill 1.1176)
			(layers "*.Cu" "*.Mask")
			(remove_unused_layers no)
			(net "GND")
			(clearance 0)
		)
		(pad "G3" thru_hole circle
			(at 2.400046 0 180)
			(size 1.6256 1.6256)
			(drill 1.1176)
			(layers "*.Cu" "*.Mask")
			(remove_unused_layers no)
			(net "GND")
			(clearance 0)
		)
		(pad "G4" thru_hole circle
			(at 2.400046 12.5349 180)
			(size 1.6256 1.6256)
			(drill 1.1176)
			(layers "*.Cu" "*.Mask")
			(remove_unused_layers no)
			(net "GND")
			(clearance 0)
		)
		(pad "G5" thru_hole circle
			(at 2.400046 32.759904 180)
			(size 1.6256 1.6256)
			(drill 1.1176)
			(layers "*.Cu" "*.Mask")
			(remove_unused_layers no)
			(net "GND")
			(clearance 0)
		)
		(pad "OA1" smd rect
			(at -2.750058 -30.660086 180)
			(size 0.381 1.4478)
			(layers "F.Cu" "F.Mask" "F.Paste")
			(net "P12V_SCM")
		)
		(pad "OA2" smd rect
			(at -2.750058 -30.059884 180)
			(size 0.381 1.4478)
			(layers "F.Cu" "F.Mask" "F.Paste")
			(net "P12V_SCM")
		)
		(pad "OA3" smd rect
			(at -2.750058 -29.459936 180)
			(size 0.381 1.4478)
			(layers "F.Cu" "F.Mask" "F.Paste")
			(net "GND")
		)
		(pad "OA4" smd rect
			(at -2.750058 -28.859988 180)
			(size 0.381 1.4478)
			(layers "F.Cu" "F.Mask" "F.Paste")
			(net "GND")
		)
		(pad "OA5" smd rect
			(at -2.750058 -28.26004 180)
			(size 0.381 1.4478)
			(layers "F.Cu" "F.Mask" "F.Paste")
			(net "I3C_SPD_DDRABCD_CPU0_BMC_R_SCL")
		)
		(pad "OA6" smd rect
			(at -2.750058 -27.660092 180)
			(size 0.381 1.4478)
			(layers "F.Cu" "F.Mask" "F.Paste")
			(net "I3C_SPD_DDRABCD_CPU0_BMC_R_SDA")
		)
		(pad "OA7" smd rect
			(at -2.750058 -27.05989 180)
			(size 0.381 1.4478)
			(layers "F.Cu" "F.Mask" "F.Paste")
			(net "I3C_SPD_DDREFGH_CPU0_BMC_R_SCL")
		)
		(pad "OA8" smd rect
			(at -2.750058 -26.459942 180)
			(size 0.381 1.4478)
			(layers "F.Cu" "F.Mask" "F.Paste")
			(net "I3C_SPD_DDREFGH_CPU0_BMC_R_SDA")
		)
		(pad "OA9" smd rect
			(at -2.750058 -25.859994 180)
			(size 0.381 1.4478)
			(layers "F.Cu" "F.Mask" "F.Paste")
			(net "I3C_SPD_DDRABCD_CPU1_BMC_R_SCL")
		)
		(pad "OA10" smd rect
			(at -2.750058 -25.260046 180)
			(size 0.381 1.4478)
			(layers "F.Cu" "F.Mask" "F.Paste")
			(net "I3C_SPD_DDRABCD_CPU1_BMC_R_SDA")
		)
		(pad "OA11" smd rect
			(at -2.750058 -24.660098 180)
			(size 0.381 1.4478)
			(layers "F.Cu" "F.Mask" "F.Paste")
			(net "I3C_SPD_DDREFGH_CPU1_BMC_R_SCL")
		)
		(pad "OA12" smd rect
			(at -2.750058 -24.059896 180)
			(size 0.381 1.4478)
			(layers "F.Cu" "F.Mask" "F.Paste")
			(net "I3C_SPD_DDREFGH_CPU1_BMC_R_SDA")
		)
		(pad "OA13" smd rect
			(at -2.750058 -23.459948 180)
			(size 0.381 1.4478)
			(layers "F.Cu" "F.Mask" "F.Paste")
			(net "GND")
		)
		(pad "OA14" smd rect
			(at -2.750058 -22.86 180)
			(size 0.381 1.4478)
			(layers "F.Cu" "F.Mask" "F.Paste")
			(net "VIRTUAL_RESEAT")
		)
		(pad "OB1" smd rect
			(at -5.700014 -30.660086 180)
			(size 0.381 1.4478)
			(layers "F.Cu" "F.Mask" "F.Paste")
			(net "P12V_SCM")
		)
		(pad "OB2" smd rect
			(at -5.700014 -30.059884 180)
			(size 0.381 1.4478)
			(layers "F.Cu" "F.Mask" "F.Paste")
			(net "P12V_SCM")
		)
		(pad "OB3" smd rect
			(at -5.700014 -29.459936 180)
			(size 0.381 1.4478)
			(layers "F.Cu" "F.Mask" "F.Paste")
			(net "PRSNT0_N")
		)
		(pad "OB4" smd rect
			(at -5.700014 -28.859988 180)
			(size 0.381 1.4478)
			(layers "F.Cu" "F.Mask" "F.Paste")
			(net "GND")
		)
		(pad "OB5" smd rect
			(at -5.700014 -28.26004 180)
			(size 0.381 1.4478)
			(layers "F.Cu" "F.Mask" "F.Paste")
			(net "UART_BMC_BIC_TX")
		)
		(pad "OB6" smd rect
			(at -5.700014 -27.660092 180)
			(size 0.381 1.4478)
			(layers "F.Cu" "F.Mask" "F.Paste")
			(net "UART_BMC_BIC_BUF_RX")
		)
		(pad "OB7" smd rect
			(at -5.700014 -27.05989 180)
			(size 0.381 1.4478)
			(layers "F.Cu" "F.Mask" "F.Paste")
			(net "GND")
		)
		(pad "OB8" smd rect
			(at -5.700014 -26.459942 180)
			(size 0.381 1.4478)
			(layers "F.Cu" "F.Mask" "F.Paste")
			(net "USB2_7_R_DP")
		)
		(pad "OB9" smd rect
			(at -5.700014 -25.859994 180)
			(size 0.381 1.4478)
			(layers "F.Cu" "F.Mask" "F.Paste")
			(net "USB2_7_R_DN")
		)
		(pad "OB10" smd rect
			(at -5.700014 -25.260046 180)
			(size 0.381 1.4478)
			(layers "F.Cu" "F.Mask" "F.Paste")
			(net "GND")
		)
		(pad "OB11" smd rect
			(at -5.700014 -24.660098 180)
			(size 0.381 1.4478)
			(layers "F.Cu" "F.Mask" "F.Paste")
			(net "RST_SRST_PLD_BMC_N")
		)
		(pad "OB12" smd rect
			(at -5.700014 -24.059896 180)
			(size 0.381 1.4478)
			(layers "F.Cu" "F.Mask" "F.Paste")
			(net "SPI_TPM_CS_N")
		)
		(pad "OB13" smd rect
			(at -5.700014 -23.459948 180)
			(size 0.381 1.4478)
			(layers "F.Cu" "F.Mask" "F.Paste")
			(net "H_CPU_CATERR_LVC2_BMC_N")
		)
	)
)
